(kicad_pcb
	(version 20260206)
	(generator "pcbnew")
	(generator_version "10.0")
	(general
		(thickness 1.6)
		(legacy_teardrops no)
	)
	(paper "A4")
	(title_block
		(title "Bryce Canyon_IOM_M2_16342-2_OCP.brd")
		(comment 1 "Bryce Canyon / footprints 1019-1026 of 1146")
	)
	(layers
		(0 "F.Cu" signal "TOP")
		(4 "In1.Cu" signal "L2GND")
		(6 "In2.Cu" signal "L3")
		(8 "In3.Cu" signal "L4VCC")
		(10 "In4.Cu" signal "L5VCC")
		(12 "In5.Cu" signal "L6")
		(14 "In6.Cu" signal "L7GND")
		(2 "B.Cu" signal "BOTTOM")
		(9 "F.Adhes" user "F.Adhesive")
		(11 "B.Adhes" user "B.Adhesive")
		(13 "F.Paste" user "Package Geometry/Pastemask Top")
		(15 "B.Paste" user "Package Geometry/Pastemask Bottom")
		(5 "F.SilkS" user "Ref Des/Silkscreen Top")
		(7 "B.SilkS" user "Ref Des/Silkscreen Bottom")
		(1 "F.Mask" user "Board Geometry/Soldermask Top")
		(3 "B.Mask" user "Board Geometry/Soldermask Bottom")
		(17 "Dwgs.User" user "User.Drawings")
		(19 "Cmts.User" user "User.Comments")
		(21 "Eco1.User" user "User.Eco1")
		(23 "Eco2.User" user "User.Eco2")
		(25 "Edge.Cuts" user "Board Geometry/Outline")
		(27 "Margin" user)
		(31 "F.CrtYd" user "Package Geometry/Place Bound Top")
		(29 "B.CrtYd" user "Package Geometry/Place Bound Bottom")
		(35 "F.Fab" user "Ref Des/Assembly Top")
		(33 "B.Fab" user "Ref Des/Assembly Bottom")
	)
	(footprint ""
		(layer "B.Cu")
		(at 16.6116 -139.1412 180)
		(property "Reference" "C68"
			(at 0 0 0)
			(layer "B.SilkS")
			(hide yes)
			(effects
				(font
					(size 1.27 1.27)
				)
				(justify mirror)
			)
		)
		(property "Value" "SCD1U16V2KX-3GP"
			(at -1.1811 -2.7051 180)
			(unlocked yes)
			(layer "B.Fab")
			(hide yes)
			(effects
				(font
					(size 1.016 1.016)
					(thickness 0.1524)
				)
				(justify mirror)
			)
		)
		(property "Device Type" "C402H22"
			(at -1.1811 -4.2291 180)
			(unlocked yes)
			(layer "B.Fab")
			(hide yes)
			(effects
				(font
					(size 1.016 1.016)
					(thickness 0.1524)
				)
				(justify mirror)
			)
		)
		(duplicate_pad_numbers_are_jumpers no)
		(fp_rect
			(start 0.4318 0.9525)
			(end -0.4318 -0.9525)
			(stroke
				(width 0)
				(type default)
			)
			(fill no)
			(layer "B.CrtYd")
		)
		(fp_rect
			(start 0.4318 0.9525)
			(end -0.4318 -0.9525)
			(stroke
				(width 0)
				(type default)
			)
			(fill no)
			(layer "B.Fab")
		)
		(pad "1" smd custom
			(at 0 -0.4445)
			(size 0.1524 0.1524)
			(layers "B.Cu" "B.Mask" "B.Paste")
			(net "GND")
			(options
				(clearance outline)
				(anchor circle)
			)
			(primitives
				(gr_poly
					(pts
						(arc
							(start 0.3048 0.2032)
							(mid 0.275042 0.275042)
							(end 0.2032 0.3048)
						)
						(arc
							(start -0.2032 0.3048)
							(mid -0.275042 0.275042)
							(end -0.3048 0.2032)
						)
						(arc
							(start -0.3048 -0.2032)
							(mid -0.275042 -0.275042)
							(end -0.2032 -0.3048)
						)
						(arc
							(start 0.2032 -0.3048)
							(mid 0.275042 -0.275042)
							(end 0.3048 -0.2032)
						)
					)
					(width 0)
					(fill yes)
				)
			)
		)
		(pad "2" smd custom
			(at 0 0.4445)
			(size 0.1524 0.1524)
			(layers "B.Cu" "B.Mask" "B.Paste")
			(net "DDR_VREF")
			(options
				(clearance outline)
				(anchor circle)
			)
			(primitives
				(gr_poly
					(pts
						(arc
							(start 0.3048 0.2032)
							(mid 0.275042 0.275042)
							(end 0.2032 0.3048)
						)
						(arc
							(start -0.2032 0.3048)
							(mid -0.275042 0.275042)
							(end -0.3048 0.2032)
						)
						(arc
							(start -0.3048 -0.2032)
							(mid -0.275042 -0.275042)
							(end -0.2032 -0.3048)
						)
						(arc
							(start 0.2032 -0.3048)
							(mid 0.275042 -0.275042)
							(end 0.3048 -0.2032)
						)
					)
					(width 0)
					(fill yes)
				)
			)
		)
	)
	(footprint ""
		(layer "B.Cu")
		(at 222.452692 -99.449382 90)
		(property "Reference" "R832"
			(at 0 0 90)
			(layer "B.SilkS")
			(hide yes)
			(effects
				(font
					(size 1.27 1.27)
				)
				(justify mirror)
			)
		)
		(property "Value" "2D2R3-1-U-GP"
			(at 0.0254 -2.5146 90)
			(unlocked yes)
			(layer "B.Fab")
			(hide yes)
			(effects
				(font
					(size 1.016 1.016)
					(thickness 0.1524)
				)
				(justify mirror)
			)
		)
		(property "Device Type" "R603H22"
			(at 0.0254 -4.0386 90)
			(unlocked yes)
			(layer "B.Fab")
			(hide yes)
			(effects
				(font
					(size 1.016 1.016)
					(thickness 0.1524)
				)
				(justify mirror)
			)
		)
		(duplicate_pad_numbers_are_jumpers no)
		(fp_line
			(start 0.4826 0)
			(end 0.2032 0)
			(stroke
				(width 0.2032)
				(type default)
			)
			(layer "B.SilkS")
		)
		(fp_line
			(start -0.2032 0)
			(end -0.4826 0)
			(stroke
				(width 0.2032)
				(type default)
			)
			(layer "B.SilkS")
		)
		(fp_rect
			(start 0.5842 1.3335)
			(end -0.5842 -1.3335)
			(stroke
				(width 0)
				(type default)
			)
			(fill no)
			(layer "B.CrtYd")
		)
		(fp_rect
			(start 0.5842 1.3335)
			(end -0.5842 -1.3335)
			(stroke
				(width 0)
				(type default)
			)
			(fill no)
			(layer "B.Fab")
		)
		(pad "1" smd custom
			(at 0 -0.762 270)
			(size 0.2159 0.2159)
			(layers "B.Cu" "B.Mask" "B.Paste")
			(net "P12V_STBY_VDD_U81")
			(options
				(clearance outline)
				(anchor circle)
			)
			(primitives
				(gr_poly
					(pts
						(arc
							(start -0.3302 0.4318)
							(mid -0.402042 0.402042)
							(end -0.4318 0.3302)
						)
						(arc
							(start -0.4318 -0.3302)
							(mid -0.402042 -0.402042)
							(end -0.3302 -0.4318)
						)
						(arc
							(start 0.3302 -0.4318)
							(mid 0.402042 -0.402042)
							(end 0.4318 -0.3302)
						)
						(arc
							(start 0.4318 0.3302)
							(mid 0.402042 0.402042)
							(end 0.3302 0.4318)
						)
					)
					(width 0)
					(fill yes)
				)
			)
		)
		(pad "2" smd custom
			(at 0 0.762 270)
			(size 0.2159 0.2159)
			(layers "B.Cu" "B.Mask" "B.Paste")
			(net "P12V_STBY")
			(options
				(clearance outline)
				(anchor circle)
			)
			(primitives
				(gr_poly
					(pts
						(arc
							(start -0.3302 0.4318)
							(mid -0.402042 0.402042)
							(end -0.4318 0.3302)
						)
						(arc
							(start -0.4318 -0.3302)
							(mid -0.402042 -0.402042)
							(end -0.3302 -0.4318)
						)
						(arc
							(start 0.3302 -0.4318)
							(mid 0.402042 -0.402042)
							(end 0.4318 -0.3302)
						)
						(arc
							(start 0.4318 0.3302)
							(mid 0.402042 0.402042)
							(end 0.3302 0.4318)
						)
					)
					(width 0)
					(fill yes)
				)
			)
		)
	)
	(footprint ""
		(layer "B.Cu")
		(at 49.458372 -158.570676 180)
		(property "Reference" "R297"
			(at 0 0 0)
			(layer "B.SilkS")
			(hide yes)
			(effects
				(font
					(size 1.27 1.27)
				)
				(justify mirror)
			)
		)
		(property "Value" "0R2J-2-GP"
			(at -0.064008 -3.993896 180)
			(unlocked yes)
			(layer "B.Fab")
			(hide yes)
			(effects
				(font
					(size 1.016 1.016)
					(thickness 0.1524)
				)
				(justify mirror)
			)
		)
		(property "Device Type" "R402H16"
			(at -0.064008 -5.517896 180)
			(unlocked yes)
			(layer "B.Fab")
			(hide yes)
			(effects
				(font
					(size 1.016 1.016)
					(thickness 0.1524)
				)
				(justify mirror)
			)
		)
		(duplicate_pad_numbers_are_jumpers no)
		(fp_line
			(start 0.508 -0.9398)
			(end 0.508 0.9398)
			(stroke
				(width 0.1524)
				(type default)
			)
			(layer "B.SilkS")
		)
		(fp_line
			(start -0.508 -0.9398)
			(end 0.508 -0.9398)
			(stroke
				(width 0.1524)
				(type default)
			)
			(layer "B.SilkS")
		)
		(fp_rect
			(start 0.508 0.9398)
			(end -0.508 -0.9398)
			(stroke
				(width 0)
				(type default)
			)
			(fill no)
			(layer "B.CrtYd")
		)
		(fp_rect
			(start 0.508 0.9398)
			(end -0.508 -0.9398)
			(stroke
				(width 0)
				(type default)
			)
			(fill no)
			(layer "B.Fab")
		)
		(pad "1" smd custom
			(at 0 -0.4445)
			(size 0.1397 0.1397)
			(layers "B.Cu" "B.Mask" "B.Paste")
			(net "UART_BMC_R_TX")
			(options
				(clearance outline)
				(anchor circle)
			)
			(primitives
				(gr_poly
					(pts
						(arc
							(start -0.1778 0.2794)
							(mid -0.249642 0.249642)
							(end -0.2794 0.1778)
						)
						(arc
							(start -0.2794 -0.1778)
							(mid -0.249642 -0.249642)
							(end -0.1778 -0.2794)
						)
						(arc
							(start 0.1778 -0.2794)
							(mid 0.249642 -0.249642)
							(end 0.2794 -0.1778)
						)
						(arc
							(start 0.2794 0.1778)
							(mid 0.249642 0.249642)
							(end 0.1778 0.2794)
						)
					)
					(width 0)
					(fill yes)
				)
			)
		)
		(pad "2" smd custom
			(at 0 0.4445)
			(size 0.1397 0.1397)
			(layers "B.Cu" "B.Mask" "B.Paste")
			(net "UART_BMC_TX")
			(options
				(clearance outline)
				(anchor circle)
			)
			(primitives
				(gr_poly
					(pts
						(arc
							(start -0.1778 0.2794)
							(mid -0.249642 0.249642)
							(end -0.2794 0.1778)
						)
						(arc
							(start -0.2794 -0.1778)
							(mid -0.249642 -0.249642)
							(end -0.1778 -0.2794)
						)
						(arc
							(start 0.1778 -0.2794)
							(mid 0.249642 -0.249642)
							(end 0.2794 -0.1778)
						)
						(arc
							(start 0.2794 0.1778)
							(mid 0.249642 0.249642)
							(end 0.1778 0.2794)
						)
					)
					(width 0)
					(fill yes)
				)
			)
		)
	)
	(footprint ""
		(layer "B.Cu")
		(at 61.4172 -157.5308 180)
		(property "Reference" "L2"
			(at 0 0 0)
			(layer "B.SilkS")
			(hide yes)
			(effects
				(font
					(size 1.27 1.27)
				)
				(justify mirror)
			)
		)
		(property "Value" "MMZ2012S601ATA1N-GP"
			(at 0 -4.2418 180)
			(unlocked yes)
			(layer "B.Fab")
			(hide yes)
			(effects
				(font
					(size 1.016 1.016)
					(thickness 0.1524)
				)
				(justify mirror)
			)
		)
		(property "Device Type" "L805H42"
			(at 0 -5.7912 180)
			(unlocked yes)
			(layer "B.Fab")
			(hide yes)
			(effects
				(font
					(size 1.016 1.016)
					(thickness 0.1524)
				)
				(justify mirror)
			)
		)
		(duplicate_pad_numbers_are_jumpers no)
		(fp_line
			(start 0.889 1.7018)
			(end 0.889 -1.7018)
			(stroke
				(width 0.1524)
				(type default)
			)
			(layer "B.SilkS")
		)
		(fp_line
			(start 0.889 -1.7018)
			(end -0.889 -1.7018)
			(stroke
				(width 0.1524)
				(type default)
			)
			(layer "B.SilkS")
		)
		(fp_line
			(start -0.889 1.7018)
			(end 0.889 1.7018)
			(stroke
				(width 0.1524)
				(type default)
			)
			(layer "B.SilkS")
		)
		(fp_line
			(start -0.889 -1.7018)
			(end -0.889 1.7018)
			(stroke
				(width 0.1524)
				(type default)
			)
			(layer "B.SilkS")
		)
		(fp_rect
			(start 0.9652 1.778)
			(end -0.9652 -1.778)
			(stroke
				(width 0)
				(type default)
			)
			(fill no)
			(layer "B.CrtYd")
		)
		(fp_rect
			(start 0.9652 1.778)
			(end -0.9652 -1.778)
			(stroke
				(width 0)
				(type default)
			)
			(fill no)
			(layer "B.Fab")
		)
		(pad "1" smd rect
			(at 0 -0.9652)
			(size 1.397 1.143)
			(layers "B.Cu" "B.Mask" "B.Paste")
			(net "P3V3_STBY")
		)
		(pad "2" smd rect
			(at 0 0.9652)
			(size 1.397 1.143)
			(layers "B.Cu" "B.Mask" "B.Paste")
			(net "ADCAV33")
		)
	)
	(footprint ""
		(layer "B.Cu")
		(at 83.9724 -128.9304)
		(property "Reference" "R718"
			(at 0 0 0)
			(layer "B.SilkS")
			(hide yes)
			(effects
				(font
					(size 1.27 1.27)
				)
				(justify mirror)
			)
		)
		(property "Value" "0R2J-2-GP"
			(at -0.064008 -3.993896 0)
			(unlocked yes)
			(layer "B.Fab")
			(hide yes)
			(effects
				(font
					(size 1.016 1.016)
					(thickness 0.1524)
				)
				(justify mirror)
			)
		)
		(property "Device Type" "R402H16"
			(at -0.064008 -5.517896 0)
			(unlocked yes)
			(layer "B.Fab")
			(hide yes)
			(effects
				(font
					(size 1.016 1.016)
					(thickness 0.1524)
				)
				(justify mirror)
			)
		)
		(duplicate_pad_numbers_are_jumpers no)
		(fp_line
			(start -0.508 -0.9398)
			(end 0.508 -0.9398)
			(stroke
				(width 0.1524)
				(type default)
			)
			(layer "B.SilkS")
		)
		(fp_line
			(start 0.508 -0.9398)
			(end 0.508 0.9398)
			(stroke
				(width 0.1524)
				(type default)
			)
			(layer "B.SilkS")
		)
		(fp_rect
			(start 0.508 0.9398)
			(end -0.508 -0.9398)
			(stroke
				(width 0)
				(type default)
			)
			(fill no)
			(layer "B.CrtYd")
		)
		(fp_rect
			(start 0.508 0.9398)
			(end -0.508 -0.9398)
			(stroke
				(width 0)
				(type default)
			)
			(fill no)
			(layer "B.Fab")
		)
		(pad "1" smd custom
			(at 0 -0.4445 180)
			(size 0.1397 0.1397)
			(layers "B.Cu" "B.Mask" "B.Paste")
			(net "BMC_TO_EXP_RESET_OUT_R")
			(options
				(clearance outline)
				(anchor circle)
			)
			(primitives
				(gr_poly
					(pts
						(arc
							(start -0.1778 0.2794)
							(mid -0.249642 0.249642)
							(end -0.2794 0.1778)
						)
						(arc
							(start -0.2794 -0.1778)
							(mid -0.249642 -0.249642)
							(end -0.1778 -0.2794)
						)
						(arc
							(start 0.1778 -0.2794)
							(mid 0.249642 -0.249642)
							(end 0.2794 -0.1778)
						)
						(arc
							(start 0.2794 0.1778)
							(mid 0.249642 0.249642)
							(end 0.1778 0.2794)
						)
					)
					(width 0)
					(fill yes)
				)
			)
		)
		(pad "2" smd custom
			(at 0 0.4445 180)
			(size 0.1397 0.1397)
			(layers "B.Cu" "B.Mask" "B.Paste")
			(net "BMC_TO_EXP_RESET_OUT")
			(options
				(clearance outline)
				(anchor circle)
			)
			(primitives
				(gr_poly
					(pts
						(arc
							(start -0.1778 0.2794)
							(mid -0.249642 0.249642)
							(end -0.2794 0.1778)
						)
						(arc
							(start -0.2794 -0.1778)
							(mid -0.249642 -0.249642)
							(end -0.1778 -0.2794)
						)
						(arc
							(start 0.1778 -0.2794)
							(mid 0.249642 -0.249642)
							(end 0.2794 -0.1778)
						)
						(arc
							(start 0.2794 0.1778)
							(mid 0.249642 0.249642)
							(end 0.1778 0.2794)
						)
					)
					(width 0)
					(fill yes)
				)
			)
		)
	)
	(footprint ""
		(layer "B.Cu")
		(at 38.419278 -153.050748 -90)
		(property "Reference" "R321"
			(at 0 0 90)
			(layer "B.SilkS")
			(hide yes)
			(effects
				(font
					(size 1.27 1.27)
				)
				(justify mirror)
			)
		)
		(property "Value" "0R2J-2-GP"
			(at -0.064008 -3.993896 270)
			(unlocked yes)
			(layer "B.Fab")
			(hide yes)
			(effects
				(font
					(size 1.016 1.016)
					(thickness 0.1524)
				)
				(justify mirror)
			)
		)
		(property "Device Type" "R402H16"
			(at -0.064008 -5.517896 270)
			(unlocked yes)
			(layer "B.Fab")
			(hide yes)
			(effects
				(font
					(size 1.016 1.016)
					(thickness 0.1524)
				)
				(justify mirror)
			)
		)
		(duplicate_pad_numbers_are_jumpers no)
		(fp_line
			(start -0.508 -0.9398)
			(end 0.508 -0.9398)
			(stroke
				(width 0.1524)
				(type default)
			)
			(layer "B.SilkS")
		)
		(fp_line
			(start 0.508 -0.9398)
			(end 0.508 0.9398)
			(stroke
				(width 0.1524)
				(type default)
			)
			(layer "B.SilkS")
		)
		(fp_rect
			(start 0.508 0.9398)
			(end -0.508 -0.9398)
			(stroke
				(width 0)
				(type default)
			)
			(fill no)
			(layer "B.CrtYd")
		)
		(fp_rect
			(start 0.508 0.9398)
			(end -0.508 -0.9398)
			(stroke
				(width 0)
				(type default)
			)
			(fill no)
			(layer "B.Fab")
		)
		(pad "1" smd custom
			(at 0 -0.4445 90)
			(size 0.1397 0.1397)
			(layers "B.Cu" "B.Mask" "B.Paste")
			(net "SCC_B_HB_IN_R")
			(options
				(clearance outline)
				(anchor circle)
			)
			(primitives
				(gr_poly
					(pts
						(arc
							(start -0.1778 0.2794)
							(mid -0.249642 0.249642)
							(end -0.2794 0.1778)
						)
						(arc
							(start -0.2794 -0.1778)
							(mid -0.249642 -0.249642)
							(end -0.1778 -0.2794)
						)
						(arc
							(start 0.1778 -0.2794)
							(mid 0.249642 -0.249642)
							(end 0.2794 -0.1778)
						)
						(arc
							(start 0.2794 0.1778)
							(mid 0.249642 0.249642)
							(end 0.1778 0.2794)
						)
					)
					(width 0)
					(fill yes)
				)
			)
		)
		(pad "2" smd custom
			(at 0 0.4445 90)
			(size 0.1397 0.1397)
			(layers "B.Cu" "B.Mask" "B.Paste")
			(net "SCC_RMT_HEARTBEAT")
			(options
				(clearance outline)
				(anchor circle)
			)
			(primitives
				(gr_poly
					(pts
						(arc
							(start -0.1778 0.2794)
							(mid -0.249642 0.249642)
							(end -0.2794 0.1778)
						)
						(arc
							(start -0.2794 -0.1778)
							(mid -0.249642 -0.249642)
							(end -0.1778 -0.2794)
						)
						(arc
							(start 0.1778 -0.2794)
							(mid 0.249642 -0.249642)
							(end 0.2794 -0.1778)
						)
						(arc
							(start 0.2794 0.1778)
							(mid 0.249642 0.249642)
							(end 0.1778 0.2794)
						)
					)
					(width 0)
					(fill yes)
				)
			)
		)
	)
	(footprint ""
		(layer "B.Cu")
		(at 40.9956 -157.4546 -90)
		(property "Reference" "R326"
			(at 0 0 90)
			(layer "B.SilkS")
			(hide yes)
			(effects
				(font
					(size 1.27 1.27)
				)
				(justify mirror)
			)
		)
		(property "Value" "0R2J-2-GP"
			(at -0.064008 -3.993896 270)
			(unlocked yes)
			(layer "B.Fab")
			(hide yes)
			(effects
				(font
					(size 1.016 1.016)
					(thickness 0.1524)
				)
				(justify mirror)
			)
		)
		(property "Device Type" "R402H16"
			(at -0.064008 -5.517896 270)
			(unlocked yes)
			(layer "B.Fab")
			(hide yes)
			(effects
				(font
					(size 1.016 1.016)
					(thickness 0.1524)
				)
				(justify mirror)
			)
		)
		(duplicate_pad_numbers_are_jumpers no)
		(fp_line
			(start -0.508 -0.9398)
			(end 0.508 -0.9398)
			(stroke
				(width 0.1524)
				(type default)
			)
			(layer "B.SilkS")
		)
		(fp_line
			(start 0.508 -0.9398)
			(end 0.508 0.9398)
			(stroke
				(width 0.1524)
				(type default)
			)
			(layer "B.SilkS")
		)
		(fp_rect
			(start 0.508 0.9398)
			(end -0.508 -0.9398)
			(stroke
				(width 0)
				(type default)
			)
			(fill no)
			(layer "B.CrtYd")
		)
		(fp_rect
			(start 0.508 0.9398)
			(end -0.508 -0.9398)
			(stroke
				(width 0)
				(type default)
			)
			(fill no)
			(layer "B.Fab")
		)
		(pad "1" smd custom
			(at 0 -0.4445 90)
			(size 0.1397 0.1397)
			(layers "B.Cu" "B.Mask" "B.Paste")
			(net "BMC_LOC_HB")
			(options
				(clearance outline)
				(anchor circle)
			)
			(primitives
				(gr_poly
					(pts
						(arc
							(start -0.1778 0.2794)
							(mid -0.249642 0.249642)
							(end -0.2794 0.1778)
						)
						(arc
							(start -0.2794 -0.1778)
							(mid -0.249642 -0.249642)
							(end -0.1778 -0.2794)
						)
						(arc
							(start 0.1778 -0.2794)
							(mid 0.249642 -0.249642)
							(end 0.2794 -0.1778)
						)
						(arc
							(start 0.2794 0.1778)
							(mid 0.249642 0.249642)
							(end 0.1778 0.2794)
						)
					)
					(width 0)
					(fill yes)
				)
			)
		)
		(pad "2" smd custom
			(at 0 0.4445 90)
			(size 0.1397 0.1397)
			(layers "B.Cu" "B.Mask" "B.Paste")
			(net "BMC_LOC_HEARTBEAT")
			(options
				(clearance outline)
				(anchor circle)
			)
			(primitives
				(gr_poly
					(pts
						(arc
							(start -0.1778 0.2794)
							(mid -0.249642 0.249642)
							(end -0.2794 0.1778)
						)
						(arc
							(start -0.2794 -0.1778)
							(mid -0.249642 -0.249642)
							(end -0.1778 -0.2794)
						)
						(arc
							(start 0.1778 -0.2794)
							(mid 0.249642 -0.249642)
							(end 0.2794 -0.1778)
						)
						(arc
							(start 0.2794 0.1778)
							(mid 0.249642 0.249642)
							(end 0.1778 0.2794)
						)
					)
					(width 0)
					(fill yes)
				)
			)
		)
	)
	(footprint ""
		(layer "B.Cu")
		(at 56.716168 -144.018)
		(property "Reference" "TP79"
			(at 0 0 0)
			(layer "B.SilkS")
			(hide yes)
			(effects
				(font
					(size 1.27 1.27)
				)
				(justify mirror)
			)
		)
		(property "Value" "TPAD28-2-GP"
			(at 0.0127 -1.6637 0)
			(unlocked yes)
			(layer "B.Fab")
			(hide yes)
			(effects
				(font
					(size 1.016 1.016)
					(thickness 0.1524)
				)
				(justify mirror)
			)
		)
		(property "Device Type" "TPAD28"
			(at 0.0127 -3.1877 0)
			(unlocked yes)
			(layer "B.Fab")
			(hide yes)
			(effects
				(font
					(size 1.016 1.016)
					(thickness 0.1524)
				)
				(justify mirror)
			)
		)
		(duplicate_pad_numbers_are_jumpers no)
		(fp_poly
			(pts
				(arc
					(start 0.3556 0)
					(mid -0.3556 0)
					(end 0.3556 0)
				)
			)
			(stroke
				(width 0)
				(type default)
			)
			(fill no)
			(layer "B.CrtYd")
		)
		(fp_poly
			(pts
				(arc
					(start 0.6096 0)
					(mid -0.6096 0)
					(end 0.6096 0)
				)
			)
			(stroke
				(width 0)
				(type default)
			)
			(fill no)
			(layer "B.Fab")
		)
		(pad "1" smd circle
			(at 0 0 180)
			(size 0.7112 0.7112)
			(layers "B.Cu" "B.Mask" "B.Paste")
			(net "JTAG_BMC_TDI")
		)
	)
)
